(kicad_pcb
	(version 20260206)
	(generator "pcbnew")
	(generator_version "10.0")
	(general
		(thickness 1.6)
		(legacy_teardrops no)
	)
	(paper "A4")
	(title_block
		(title "peb — Lightning_PEB_BRD.brd")
		(comment 1 "Lightning (Wiwynn / Facebook NVMe JBOF) / footprints 1997-2004 of 2563")
	)
	(layers
		(0 "F.Cu" signal "TOP")
		(4 "In1.Cu" signal "L2GND")
		(6 "In2.Cu" signal "L3")
		(8 "In3.Cu" signal "L4VCC")
		(10 "In4.Cu" signal "L5VCC")
		(12 "In5.Cu" signal "L6")
		(14 "In6.Cu" signal "L7GND")
		(2 "B.Cu" signal "BOTTOM")
		(9 "F.Adhes" user "F.Adhesive")
		(11 "B.Adhes" user "B.Adhesive")
		(13 "F.Paste" user "Package Geometry/Pastemask Top")
		(15 "B.Paste" user "Package Geometry/Pastemask Bottom")
		(5 "F.SilkS" user "Ref Des/Silkscreen Top")
		(7 "B.SilkS" user "Ref Des/Silkscreen Bottom")
		(1 "F.Mask" user "Board Geometry/Soldermask Top")
		(3 "B.Mask" user "Board Geometry/Soldermask Bottom")
		(17 "Dwgs.User" user "User.Drawings")
		(19 "Cmts.User" user "User.Comments")
		(21 "Eco1.User" user "User.Eco1")
		(23 "Eco2.User" user "User.Eco2")
		(25 "Edge.Cuts" user "Board Geometry/Outline")
		(27 "Margin" user)
		(31 "F.CrtYd" user "Package Geometry/Place Bound Top")
		(29 "B.CrtYd" user "Package Geometry/Place Bound Bottom")
		(35 "F.Fab" user "Ref Des/Assembly Top")
		(33 "B.Fab" user "Ref Des/Assembly Bottom")
	)
	(footprint ""
		(layer "B.Cu")
		(at 228.1682 -194.4116 90)
		(property "Reference" "R3239"
			(at 0 0 90)
			(layer "B.SilkS")
			(hide yes)
			(effects
				(font
					(size 1.27 1.27)
				)
				(justify mirror)
			)
		)
		(property "Value" "0R2J-2-GP"
			(at -0.064008 -3.993896 90)
			(unlocked yes)
			(layer "B.Fab")
			(hide yes)
			(effects
				(font
					(size 1.016 1.016)
					(thickness 0.1524)
				)
				(justify mirror)
			)
		)
		(property "Device Type" "R402H16"
			(at -0.064008 -5.517896 90)
			(unlocked yes)
			(layer "B.Fab")
			(hide yes)
			(effects
				(font
					(size 1.016 1.016)
					(thickness 0.1524)
				)
				(justify mirror)
			)
		)
		(duplicate_pad_numbers_are_jumpers no)
		(fp_line
			(start 0.508 -0.9398)
			(end 0.508 0.9398)
			(stroke
				(width 0.1524)
				(type default)
			)
			(layer "B.SilkS")
		)
		(fp_line
			(start -0.508 -0.9398)
			(end 0.508 -0.9398)
			(stroke
				(width 0.1524)
				(type default)
			)
			(layer "B.SilkS")
		)
		(fp_rect
			(start 0.508 0.9398)
			(end -0.508 -0.9398)
			(stroke
				(width 0)
				(type default)
			)
			(fill no)
			(layer "B.CrtYd")
		)
		(fp_rect
			(start 0.508 0.9398)
			(end -0.508 -0.9398)
			(stroke
				(width 0)
				(type default)
			)
			(fill no)
			(layer "B.Fab")
		)
		(pad "1" smd custom
			(at 0 -0.4445 270)
			(size 0.1397 0.1397)
			(layers "B.Cu" "B.Mask" "B.Paste")
			(net "SSD_PERST_Y12")
			(options
				(clearance outline)
				(anchor circle)
			)
			(primitives
				(gr_poly
					(pts
						(arc
							(start -0.1778 0.2794)
							(mid -0.249642 0.249642)
							(end -0.2794 0.1778)
						)
						(arc
							(start -0.2794 -0.1778)
							(mid -0.249642 -0.249642)
							(end -0.1778 -0.2794)
						)
						(arc
							(start 0.1778 -0.2794)
							(mid 0.249642 -0.249642)
							(end 0.2794 -0.1778)
						)
						(arc
							(start 0.2794 0.1778)
							(mid 0.249642 0.249642)
							(end 0.1778 0.2794)
						)
					)
					(width 0)
					(fill yes)
				)
			)
		)
		(pad "2" smd custom
			(at 0 0.4445 270)
			(size 0.1397 0.1397)
			(layers "B.Cu" "B.Mask" "B.Paste")
			(net "SSD_PERST#12_R")
			(options
				(clearance outline)
				(anchor circle)
			)
			(primitives
				(gr_poly
					(pts
						(arc
							(start -0.1778 0.2794)
							(mid -0.249642 0.249642)
							(end -0.2794 0.1778)
						)
						(arc
							(start -0.2794 -0.1778)
							(mid -0.249642 -0.249642)
							(end -0.1778 -0.2794)
						)
						(arc
							(start 0.1778 -0.2794)
							(mid 0.249642 -0.249642)
							(end 0.2794 -0.1778)
						)
						(arc
							(start 0.2794 0.1778)
							(mid 0.249642 0.249642)
							(end 0.1778 0.2794)
						)
					)
					(width 0)
					(fill yes)
				)
			)
		)
	)
	(footprint ""
		(layer "B.Cu")
		(at 228.6254 -57.992772 90)
		(property "Reference" "C534"
			(at 0 0 90)
			(layer "B.SilkS")
			(hide yes)
			(effects
				(font
					(size 1.27 1.27)
				)
				(justify mirror)
			)
		)
		(property "Value" "SCD1U16V1KX-1-GP"
			(at 2.8321 -1.7399 90)
			(unlocked yes)
			(layer "B.Fab")
			(hide yes)
			(effects
				(font
					(size 1.016 1.016)
					(thickness 0.1524)
				)
				(justify mirror)
			)
		)
		(property "Device Type" "C0201H13"
			(at 2.8321 -3.2639 90)
			(unlocked yes)
			(layer "B.Fab")
			(hide yes)
			(effects
				(font
					(size 1.016 1.016)
					(thickness 0.1524)
				)
				(justify mirror)
			)
		)
		(duplicate_pad_numbers_are_jumpers no)
		(fp_rect
			(start 0.2794 0.6477)
			(end -0.2794 -0.6477)
			(stroke
				(width 0)
				(type default)
			)
			(fill no)
			(layer "B.CrtYd")
		)
		(fp_rect
			(start 0.2794 0.6477)
			(end -0.2794 -0.6477)
			(stroke
				(width 0)
				(type default)
			)
			(fill no)
			(layer "B.Fab")
		)
		(pad "1" smd custom
			(at 0 -0.2794 270)
			(size 0.0762 0.0762)
			(layers "B.Cu" "B.Mask" "B.Paste")
			(net "DUT_AVD_PCIE")
			(options
				(clearance outline)
				(anchor circle)
			)
			(primitives
				(gr_poly
					(pts
						(arc
							(start 0.1524 0.127)
							(mid 0.137521 0.162921)
							(end 0.1016 0.1778)
						)
						(arc
							(start -0.1016 0.1778)
							(mid -0.137521 0.162921)
							(end -0.1524 0.127)
						)
						(arc
							(start -0.1524 -0.127)
							(mid -0.137521 -0.162921)
							(end -0.1016 -0.1778)
						)
						(arc
							(start 0.1016 -0.1778)
							(mid 0.137521 -0.162921)
							(end 0.1524 -0.127)
						)
					)
					(width 0)
					(fill yes)
				)
			)
		)
		(pad "2" smd custom
			(at 0 0.2794 270)
			(size 0.0762 0.0762)
			(layers "B.Cu" "B.Mask" "B.Paste")
			(net "GND")
			(options
				(clearance outline)
				(anchor circle)
			)
			(primitives
				(gr_poly
					(pts
						(arc
							(start 0.1524 0.127)
							(mid 0.137521 0.162921)
							(end 0.1016 0.1778)
						)
						(arc
							(start -0.1016 0.1778)
							(mid -0.137521 0.162921)
							(end -0.1524 0.127)
						)
						(arc
							(start -0.1524 -0.127)
							(mid -0.137521 -0.162921)
							(end -0.1016 -0.1778)
						)
						(arc
							(start 0.1016 -0.1778)
							(mid 0.137521 -0.162921)
							(end 0.1524 -0.127)
						)
					)
					(width 0)
					(fill yes)
				)
			)
		)
	)
	(footprint ""
		(layer "B.Cu")
		(at 249.5423 -47.0027 90)
		(property "Reference" "C497"
			(at 0 0 90)
			(layer "B.SilkS")
			(hide yes)
			(effects
				(font
					(size 1.27 1.27)
				)
				(justify mirror)
			)
		)
		(property "Value" "SCD1U16V1KX-1-GP"
			(at 2.8321 -1.7399 90)
			(unlocked yes)
			(layer "B.Fab")
			(hide yes)
			(effects
				(font
					(size 1.016 1.016)
					(thickness 0.1524)
				)
				(justify mirror)
			)
		)
		(property "Device Type" "C0201H13"
			(at 2.8321 -3.2639 90)
			(unlocked yes)
			(layer "B.Fab")
			(hide yes)
			(effects
				(font
					(size 1.016 1.016)
					(thickness 0.1524)
				)
				(justify mirror)
			)
		)
		(duplicate_pad_numbers_are_jumpers no)
		(fp_rect
			(start 0.2794 0.6477)
			(end -0.2794 -0.6477)
			(stroke
				(width 0)
				(type default)
			)
			(fill no)
			(layer "B.CrtYd")
		)
		(fp_rect
			(start 0.2794 0.6477)
			(end -0.2794 -0.6477)
			(stroke
				(width 0)
				(type default)
			)
			(fill no)
			(layer "B.Fab")
		)
		(pad "1" smd custom
			(at 0 -0.2794 270)
			(size 0.0762 0.0762)
			(layers "B.Cu" "B.Mask" "B.Paste")
			(net "DUT_AVD_PCIE_Q")
			(options
				(clearance outline)
				(anchor circle)
			)
			(primitives
				(gr_poly
					(pts
						(arc
							(start 0.1524 0.127)
							(mid 0.137521 0.162921)
							(end 0.1016 0.1778)
						)
						(arc
							(start -0.1016 0.1778)
							(mid -0.137521 0.162921)
							(end -0.1524 0.127)
						)
						(arc
							(start -0.1524 -0.127)
							(mid -0.137521 -0.162921)
							(end -0.1016 -0.1778)
						)
						(arc
							(start 0.1016 -0.1778)
							(mid 0.137521 -0.162921)
							(end 0.1524 -0.127)
						)
					)
					(width 0)
					(fill yes)
				)
			)
		)
		(pad "2" smd custom
			(at 0 0.2794 270)
			(size 0.0762 0.0762)
			(layers "B.Cu" "B.Mask" "B.Paste")
			(net "GND")
			(options
				(clearance outline)
				(anchor circle)
			)
			(primitives
				(gr_poly
					(pts
						(arc
							(start 0.1524 0.127)
							(mid 0.137521 0.162921)
							(end 0.1016 0.1778)
						)
						(arc
							(start -0.1016 0.1778)
							(mid -0.137521 0.162921)
							(end -0.1524 0.127)
						)
						(arc
							(start -0.1524 -0.127)
							(mid -0.137521 -0.162921)
							(end -0.1016 -0.1778)
						)
						(arc
							(start 0.1016 -0.1778)
							(mid 0.137521 -0.162921)
							(end 0.1524 -0.127)
						)
					)
					(width 0)
					(fill yes)
				)
			)
		)
	)
	(footprint ""
		(layer "B.Cu")
		(at 235.585 -57.995058 -90)
		(property "Reference" "C503"
			(at 0 0 90)
			(layer "B.SilkS")
			(hide yes)
			(effects
				(font
					(size 1.27 1.27)
				)
				(justify mirror)
			)
		)
		(property "Value" "SCD1U16V1KX-1-GP"
			(at 2.8321 -1.7399 270)
			(unlocked yes)
			(layer "B.Fab")
			(hide yes)
			(effects
				(font
					(size 1.016 1.016)
					(thickness 0.1524)
				)
				(justify mirror)
			)
		)
		(property "Device Type" "C0201H13"
			(at 2.8321 -3.2639 270)
			(unlocked yes)
			(layer "B.Fab")
			(hide yes)
			(effects
				(font
					(size 1.016 1.016)
					(thickness 0.1524)
				)
				(justify mirror)
			)
		)
		(duplicate_pad_numbers_are_jumpers no)
		(fp_rect
			(start 0.2794 0.6477)
			(end -0.2794 -0.6477)
			(stroke
				(width 0)
				(type default)
			)
			(fill no)
			(layer "B.CrtYd")
		)
		(fp_rect
			(start 0.2794 0.6477)
			(end -0.2794 -0.6477)
			(stroke
				(width 0)
				(type default)
			)
			(fill no)
			(layer "B.Fab")
		)
		(pad "1" smd custom
			(at 0 -0.2794 90)
			(size 0.0762 0.0762)
			(layers "B.Cu" "B.Mask" "B.Paste")
			(net "DUT_AVD_TX")
			(options
				(clearance outline)
				(anchor circle)
			)
			(primitives
				(gr_poly
					(pts
						(arc
							(start 0.1524 0.127)
							(mid 0.137521 0.162921)
							(end 0.1016 0.1778)
						)
						(arc
							(start -0.1016 0.1778)
							(mid -0.137521 0.162921)
							(end -0.1524 0.127)
						)
						(arc
							(start -0.1524 -0.127)
							(mid -0.137521 -0.162921)
							(end -0.1016 -0.1778)
						)
						(arc
							(start 0.1016 -0.1778)
							(mid 0.137521 -0.162921)
							(end 0.1524 -0.127)
						)
					)
					(width 0)
					(fill yes)
				)
			)
		)
		(pad "2" smd custom
			(at 0 0.2794 90)
			(size 0.0762 0.0762)
			(layers "B.Cu" "B.Mask" "B.Paste")
			(net "GND")
			(options
				(clearance outline)
				(anchor circle)
			)
			(primitives
				(gr_poly
					(pts
						(arc
							(start 0.1524 0.127)
							(mid 0.137521 0.162921)
							(end 0.1016 0.1778)
						)
						(arc
							(start -0.1016 0.1778)
							(mid -0.137521 0.162921)
							(end -0.1524 0.127)
						)
						(arc
							(start -0.1524 -0.127)
							(mid -0.137521 -0.162921)
							(end -0.1016 -0.1778)
						)
						(arc
							(start 0.1016 -0.1778)
							(mid 0.137521 -0.162921)
							(end 0.1524 -0.127)
						)
					)
					(width 0)
					(fill yes)
				)
			)
		)
	)
	(footprint ""
		(layer "B.Cu")
		(at 245.1354 -54.0004 90)
		(property "Reference" "C44"
			(at 0 0 90)
			(layer "B.SilkS")
			(hide yes)
			(effects
				(font
					(size 1.27 1.27)
				)
				(justify mirror)
			)
		)
		(property "Value" "SCD1U16V1KX-1-GP"
			(at 2.8321 -1.7399 90)
			(unlocked yes)
			(layer "B.Fab")
			(hide yes)
			(effects
				(font
					(size 1.016 1.016)
					(thickness 0.1524)
				)
				(justify mirror)
			)
		)
		(property "Device Type" "C0201H13"
			(at 2.8321 -3.2639 90)
			(unlocked yes)
			(layer "B.Fab")
			(hide yes)
			(effects
				(font
					(size 1.016 1.016)
					(thickness 0.1524)
				)
				(justify mirror)
			)
		)
		(duplicate_pad_numbers_are_jumpers no)
		(fp_rect
			(start 0.2794 0.6477)
			(end -0.2794 -0.6477)
			(stroke
				(width 0)
				(type default)
			)
			(fill no)
			(layer "B.CrtYd")
		)
		(fp_rect
			(start 0.2794 0.6477)
			(end -0.2794 -0.6477)
			(stroke
				(width 0)
				(type default)
			)
			(fill no)
			(layer "B.Fab")
		)
		(pad "1" smd custom
			(at 0 -0.2794 270)
			(size 0.0762 0.0762)
			(layers "B.Cu" "B.Mask" "B.Paste")
			(net "DUT_VDD")
			(options
				(clearance outline)
				(anchor circle)
			)
			(primitives
				(gr_poly
					(pts
						(arc
							(start 0.1524 0.127)
							(mid 0.137521 0.162921)
							(end 0.1016 0.1778)
						)
						(arc
							(start -0.1016 0.1778)
							(mid -0.137521 0.162921)
							(end -0.1524 0.127)
						)
						(arc
							(start -0.1524 -0.127)
							(mid -0.137521 -0.162921)
							(end -0.1016 -0.1778)
						)
						(arc
							(start 0.1016 -0.1778)
							(mid 0.137521 -0.162921)
							(end 0.1524 -0.127)
						)
					)
					(width 0)
					(fill yes)
				)
			)
		)
		(pad "2" smd custom
			(at 0 0.2794 270)
			(size 0.0762 0.0762)
			(layers "B.Cu" "B.Mask" "B.Paste")
			(net "GND")
			(options
				(clearance outline)
				(anchor circle)
			)
			(primitives
				(gr_poly
					(pts
						(arc
							(start 0.1524 0.127)
							(mid 0.137521 0.162921)
							(end 0.1016 0.1778)
						)
						(arc
							(start -0.1016 0.1778)
							(mid -0.137521 0.162921)
							(end -0.1524 0.127)
						)
						(arc
							(start -0.1524 -0.127)
							(mid -0.137521 -0.162921)
							(end -0.1016 -0.1778)
						)
						(arc
							(start 0.1016 -0.1778)
							(mid 0.137521 -0.162921)
							(end 0.1524 -0.127)
						)
					)
					(width 0)
					(fill yes)
				)
			)
		)
	)
	(footprint ""
		(layer "B.Cu")
		(at 233.68 -23.241 180)
		(property "Reference" "R788"
			(at 0 0 0)
			(layer "B.SilkS")
			(hide yes)
			(effects
				(font
					(size 1.27 1.27)
				)
				(justify mirror)
			)
		)
		(property "Value" "4K7R2F-GP"
			(at -0.064008 -3.993896 180)
			(unlocked yes)
			(layer "B.Fab")
			(hide yes)
			(effects
				(font
					(size 1.016 1.016)
					(thickness 0.1524)
				)
				(justify mirror)
			)
		)
		(property "Device Type" "R402H16"
			(at -0.064008 -5.517896 180)
			(unlocked yes)
			(layer "B.Fab")
			(hide yes)
			(effects
				(font
					(size 1.016 1.016)
					(thickness 0.1524)
				)
				(justify mirror)
			)
		)
		(duplicate_pad_numbers_are_jumpers no)
		(fp_line
			(start 0.508 -0.9398)
			(end 0.508 0.9398)
			(stroke
				(width 0.1524)
				(type default)
			)
			(layer "B.SilkS")
		)
		(fp_line
			(start -0.508 -0.9398)
			(end 0.508 -0.9398)
			(stroke
				(width 0.1524)
				(type default)
			)
			(layer "B.SilkS")
		)
		(fp_rect
			(start 0.508 0.9398)
			(end -0.508 -0.9398)
			(stroke
				(width 0)
				(type default)
			)
			(fill no)
			(layer "B.CrtYd")
		)
		(fp_rect
			(start 0.508 0.9398)
			(end -0.508 -0.9398)
			(stroke
				(width 0)
				(type default)
			)
			(fill no)
			(layer "B.Fab")
		)
		(pad "1" smd custom
			(at 0 -0.4445)
			(size 0.1397 0.1397)
			(layers "B.Cu" "B.Mask" "B.Paste")
			(net "BOOTSTRAP8")
			(options
				(clearance outline)
				(anchor circle)
			)
			(primitives
				(gr_poly
					(pts
						(arc
							(start -0.1778 0.2794)
							(mid -0.249642 0.249642)
							(end -0.2794 0.1778)
						)
						(arc
							(start -0.2794 -0.1778)
							(mid -0.249642 -0.249642)
							(end -0.1778 -0.2794)
						)
						(arc
							(start 0.1778 -0.2794)
							(mid 0.249642 -0.249642)
							(end 0.2794 -0.1778)
						)
						(arc
							(start 0.2794 0.1778)
							(mid 0.249642 0.249642)
							(end 0.1778 0.2794)
						)
					)
					(width 0)
					(fill yes)
				)
			)
		)
		(pad "2" smd custom
			(at 0 0.4445)
			(size 0.1397 0.1397)
			(layers "B.Cu" "B.Mask" "B.Paste")
			(net "BOOTSTRAP_R_8")
			(options
				(clearance outline)
				(anchor circle)
			)
			(primitives
				(gr_poly
					(pts
						(arc
							(start -0.1778 0.2794)
							(mid -0.249642 0.249642)
							(end -0.2794 0.1778)
						)
						(arc
							(start -0.2794 -0.1778)
							(mid -0.249642 -0.249642)
							(end -0.1778 -0.2794)
						)
						(arc
							(start 0.1778 -0.2794)
							(mid 0.249642 -0.249642)
							(end 0.2794 -0.1778)
						)
						(arc
							(start 0.2794 0.1778)
							(mid 0.249642 0.249642)
							(end 0.1778 0.2794)
						)
					)
					(width 0)
					(fill yes)
				)
			)
		)
	)
	(footprint ""
		(layer "B.Cu")
		(at 46.179994 -133.344412)
		(property "Reference" "TP318"
			(at 0 0 0)
			(layer "B.SilkS")
			(hide yes)
			(effects
				(font
					(size 1.27 1.27)
				)
				(justify mirror)
			)
		)
		(property "Value" "TPAD28-2-GP"
			(at 0.0127 -1.6637 0)
			(unlocked yes)
			(layer "B.Fab")
			(hide yes)
			(effects
				(font
					(size 1.016 1.016)
					(thickness 0.1524)
				)
				(justify mirror)
			)
		)
		(property "Device Type" "TPAD28"
			(at 0.0127 -3.1877 0)
			(unlocked yes)
			(layer "B.Fab")
			(hide yes)
			(effects
				(font
					(size 1.016 1.016)
					(thickness 0.1524)
				)
				(justify mirror)
			)
		)
		(duplicate_pad_numbers_are_jumpers no)
		(fp_poly
			(pts
				(arc
					(start 0.3556 0)
					(mid -0.3556 0)
					(end 0.3556 0)
				)
			)
			(stroke
				(width 0)
				(type default)
			)
			(fill no)
			(layer "B.CrtYd")
		)
		(fp_poly
			(pts
				(arc
					(start 0.6096 0)
					(mid -0.6096 0)
					(end 0.6096 0)
				)
			)
			(stroke
				(width 0)
				(type default)
			)
			(fill no)
			(layer "B.Fab")
		)
		(pad "1" smd circle
			(at 0 0 180)
			(size 0.7112 0.7112)
			(layers "B.Cu" "B.Mask" "B.Paste")
			(net "DACG")
		)
	)
	(footprint ""
		(layer "B.Cu")
		(at 32.58312 -120.93448)
		(property "Reference" "TP307"
			(at 0 0 0)
			(layer "B.SilkS")
			(hide yes)
			(effects
				(font
					(size 1.27 1.27)
				)
				(justify mirror)
			)
		)
		(property "Value" "TPAD28-2-GP"
			(at 0.0127 -1.6637 0)
			(unlocked yes)
			(layer "B.Fab")
			(hide yes)
			(effects
				(font
					(size 1.016 1.016)
					(thickness 0.1524)
				)
				(justify mirror)
			)
		)
		(property "Device Type" "TPAD28"
			(at 0.0127 -3.1877 0)
			(unlocked yes)
			(layer "B.Fab")
			(hide yes)
			(effects
				(font
					(size 1.016 1.016)
					(thickness 0.1524)
				)
				(justify mirror)
			)
		)
		(duplicate_pad_numbers_are_jumpers no)
		(fp_poly
			(pts
				(arc
					(start 0.3556 0)
					(mid -0.3556 0)
					(end 0.3556 0)
				)
			)
			(stroke
				(width 0)
				(type default)
			)
			(fill no)
			(layer "B.CrtYd")
		)
		(fp_poly
			(pts
				(arc
					(start 0.6096 0)
					(mid -0.6096 0)
					(end 0.6096 0)
				)
			)
			(stroke
				(width 0)
				(type default)
			)
			(fill no)
			(layer "B.Fab")
		)
		(pad "1" smd circle
			(at 0 0 180)
			(size 0.7112 0.7112)
			(layers "B.Cu" "B.Mask" "B.Paste")
			(net "TP_GPIOD4")
		)
	)
)
